# S9S_MB_2U (Grand Teton) — schematic netlist excerpt (pin names and nets, part order shuffled) for the footprints in the layout excerpt that follows; sources: Cadence DE-HDL packaged netlist, KiCad conversion of 03242023_DA0F0TMBIJ0_F0T_Motherboard_J_brd_V01_OCP.brd

R1333  Q_RES  1K 1% CHIP  pkg 0402LF  page 201 : A = GND ; B = PD_RST_RTCRST_N
R1753  Q_RES  33.2 1% CHIP  pkg 0402LF  page 222 : A = SGPIO_DI_0 ; B = SGPIO_DEBUG_PLD_DIN

(kicad_pcb
	(version 20260206)
	(generator "pcbnew")
	(generator_version "10.0")
	(general
		(thickness 1.6)
		(legacy_teardrops no)
	)
	(paper "A4")
	(title_block
		(title "03242023_DA0F0TMBIJ0_F0T_Motherboard_J_brd_V01_OCP.brd")
		(comment 1 "Grand Teton / footprints 2816-2817 of 6105")
	)
	(layers
		(0 "F.Cu" signal "TOP")
		(4 "In1.Cu" signal "GND")
		(6 "In2.Cu" signal "IN1")
		(8 "In3.Cu" signal "GND1")
		(10 "In4.Cu" signal "IN2")
		(12 "In5.Cu" signal "GND2")
		(14 "In6.Cu" signal "IN3")
		(16 "In7.Cu" signal "GND3")
		(18 "In8.Cu" signal "VCC")
		(20 "In9.Cu" signal "VCC1")
		(22 "In10.Cu" signal "GND4")
		(24 "In11.Cu" signal "IN4")
		(26 "In12.Cu" signal "GND5")
		(28 "In13.Cu" signal "IN5")
		(30 "In14.Cu" signal "GND6")
		(32 "In15.Cu" signal "IN6")
		(34 "In16.Cu" signal "GND7")
		(2 "B.Cu" signal "BOTTOM")
		(9 "F.Adhes" user "F.Adhesive")
		(11 "B.Adhes" user "B.Adhesive")
		(13 "F.Paste" user "Package Geometry/Pastemask Top")
		(15 "B.Paste" user "Package Geometry/Pastemask Bottom")
		(5 "F.SilkS" user "Ref Des/Silkscreen Top")
		(7 "B.SilkS" user "Ref Des/Silkscreen Bottom")
		(1 "F.Mask" user "Board Geometry/Soldermask Top")
		(3 "B.Mask" user "Board Geometry/Soldermask Bottom")
		(17 "Dwgs.User" user "User.Drawings")
		(19 "Cmts.User" user "User.Comments")
		(21 "Eco1.User" user "User.Eco1")
		(23 "Eco2.User" user "User.Eco2")
		(25 "Edge.Cuts" user "Board Geometry/Outline")
		(27 "Margin" user)
		(31 "F.CrtYd" user "Package Geometry/Place Bound Top")
		(29 "B.CrtYd" user "Package Geometry/Place Bound Bottom")
		(35 "F.Fab" user "Ref Des/Assembly Top")
		(33 "B.Fab" user "Ref Des/Assembly Bottom")
	)
	(footprint ""
		(layer "F.Cu")
		(at 411.35681 -29.478986 -90)
		(property "Reference" "R1333"
			(at 0 0 270)
			(layer "F.SilkS")
			(hide yes)
			(effects
				(font
					(size 1.27 1.27)
				)
			)
		)
		(property "Value" ""
			(at 0 0 270)
			(layer "F.Fab")
			(effects
				(font
					(size 1.27 1.27)
				)
			)
		)
		(duplicate_pad_numbers_are_jumpers no)
		(fp_line
			(start -0.7874 0.4064)
			(end -0.7874 -0.4064)
			(stroke
				(width 0.1524)
				(type default)
			)
			(layer "F.SilkS")
		)
		(fp_line
			(start 0.7874 0.4064)
			(end -0.7874 0.4064)
			(stroke
				(width 0.1524)
				(type default)
			)
			(layer "F.SilkS")
		)
		(fp_line
			(start -0.7874 -0.4064)
			(end 0.7874 -0.4064)
			(stroke
				(width 0.1524)
				(type default)
			)
			(layer "F.SilkS")
		)
		(fp_line
			(start 0.7874 -0.4064)
			(end 0.7874 0.4064)
			(stroke
				(width 0.1524)
				(type default)
			)
			(layer "F.SilkS")
		)
		(fp_line
			(start -0.67945 0.3048)
			(end -0.67945 -0.305054)
			(stroke
				(width 0.1)
				(type default)
			)
			(layer "F.Fab")
		)
		(fp_line
			(start -0.12065 0.3048)
			(end -0.67945 0.3048)
			(stroke
				(width 0.1)
				(type default)
			)
			(layer "F.Fab")
		)
		(fp_line
			(start 0.120396 0.3048)
			(end 0.120396 0.2794)
			(stroke
				(width 0.1)
				(type default)
			)
			(layer "F.Fab")
		)
		(fp_line
			(start 0.67945 0.3048)
			(end 0.120396 0.3048)
			(stroke
				(width 0.1)
				(type default)
			)
			(layer "F.Fab")
		)
		(fp_line
			(start -0.12065 0.2794)
			(end -0.12065 0.3048)
			(stroke
				(width 0.1)
				(type default)
			)
			(layer "F.Fab")
		)
		(fp_line
			(start 0.120396 0.2794)
			(end -0.12065 0.2794)
			(stroke
				(width 0.1)
				(type default)
			)
			(layer "F.Fab")
		)
		(fp_line
			(start -0.12065 -0.2794)
			(end 0.12065 -0.2794)
			(stroke
				(width 0.1)
				(type default)
			)
			(layer "F.Fab")
		)
		(fp_line
			(start 0.12065 -0.2794)
			(end 0.12065 -0.3048)
			(stroke
				(width 0.1)
				(type default)
			)
			(layer "F.Fab")
		)
		(fp_line
			(start 0.12065 -0.3048)
			(end 0.67945 -0.3048)
			(stroke
				(width 0.1)
				(type default)
			)
			(layer "F.Fab")
		)
		(fp_line
			(start 0.67945 -0.3048)
			(end 0.67945 0.3048)
			(stroke
				(width 0.1)
				(type default)
			)
			(layer "F.Fab")
		)
		(fp_line
			(start -0.67945 -0.305054)
			(end -0.12065 -0.305054)
			(stroke
				(width 0.1)
				(type default)
			)
			(layer "F.Fab")
		)
		(fp_line
			(start -0.12065 -0.305054)
			(end -0.12065 -0.2794)
			(stroke
				(width 0.1)
				(type default)
			)
			(layer "F.Fab")
		)
		(pad "1" smd circle
			(at -0.40005 0 270)
			(size 0 0)
			(layers "F.Cu" "F.Mask" "F.Paste")
			(net "GND")
		)
		(pad "2" smd circle
			(at 0.40005 0 270)
			(size 0 0)
			(layers "F.Cu" "F.Mask" "F.Paste")
			(net "PD_RST_RTCRST_N")
		)
	)
	(footprint ""
		(layer "F.Cu")
		(at 164.64788 -117.566948)
		(property "Reference" "R1753"
			(at 0 0 0)
			(layer "F.SilkS")
			(hide yes)
			(effects
				(font
					(size 1.27 1.27)
				)
			)
		)
		(property "Value" ""
			(at 0 0 0)
			(layer "F.Fab")
			(effects
				(font
					(size 1.27 1.27)
				)
			)
		)
		(duplicate_pad_numbers_are_jumpers no)
		(fp_line
			(start -0.7874 -0.4064)
			(end 0.7874 -0.4064)
			(stroke
				(width 0.1524)
				(type default)
			)
			(layer "F.SilkS")
		)
		(fp_line
			(start -0.7874 0.4064)
			(end -0.7874 -0.4064)
			(stroke
				(width 0.1524)
				(type default)
			)
			(layer "F.SilkS")
		)
		(fp_line
			(start 0.7874 -0.4064)
			(end 0.7874 0.4064)
			(stroke
				(width 0.1524)
				(type default)
			)
			(layer "F.SilkS")
		)
		(fp_line
			(start 0.7874 0.4064)
			(end -0.7874 0.4064)
			(stroke
				(width 0.1524)
				(type default)
			)
			(layer "F.SilkS")
		)
		(fp_line
			(start -0.67945 -0.305054)
			(end -0.12065 -0.305054)
			(stroke
				(width 0.1)
				(type default)
			)
			(layer "F.Fab")
		)
		(fp_line
			(start -0.67945 0.3048)
			(end -0.67945 -0.305054)
			(stroke
				(width 0.1)
				(type default)
			)
			(layer "F.Fab")
		)
		(fp_line
			(start -0.12065 -0.305054)
			(end -0.12065 -0.2794)
			(stroke
				(width 0.1)
				(type default)
			)
			(layer "F.Fab")
		)
		(fp_line
			(start -0.12065 -0.2794)
			(end 0.12065 -0.2794)
			(stroke
				(width 0.1)
				(type default)
			)
			(layer "F.Fab")
		)
		(fp_line
			(start -0.12065 0.2794)
			(end -0.12065 0.3048)
			(stroke
				(width 0.1)
				(type default)
			)
			(layer "F.Fab")
		)
		(fp_line
			(start -0.12065 0.3048)
			(end -0.67945 0.3048)
			(stroke
				(width 0.1)
				(type default)
			)
			(layer "F.Fab")
		)
		(fp_line
			(start 0.120396 0.2794)
			(end -0.12065 0.2794)
			(stroke
				(width 0.1)
				(type default)
			)
			(layer "F.Fab")
		)
		(fp_line
			(start 0.120396 0.3048)
			(end 0.120396 0.2794)
			(stroke
				(width 0.1)
				(type default)
			)
			(layer "F.Fab")
		)
		(fp_line
			(start 0.12065 -0.3048)
			(end 0.67945 -0.3048)
			(stroke
				(width 0.1)
				(type default)
			)
			(layer "F.Fab")
		)
		(fp_line
			(start 0.12065 -0.2794)
			(end 0.12065 -0.3048)
			(stroke
				(width 0.1)
				(type default)
			)
			(layer "F.Fab")
		)
		(fp_line
			(start 0.67945 -0.3048)
			(end 0.67945 0.3048)
			(stroke
				(width 0.1)
				(type default)
			)
			(layer "F.Fab")
		)
		(fp_line
			(start 0.67945 0.3048)
			(end 0.120396 0.3048)
			(stroke
				(width 0.1)
				(type default)
			)
			(layer "F.Fab")
		)
		(pad "1" smd circle
			(at -0.40005 0)
			(size 0 0)
			(layers "F.Cu" "F.Mask" "F.Paste")
			(net "SGPIO_DI_0")
		)
		(pad "2" smd circle
			(at 0.40005 0)
			(size 0 0)
			(layers "F.Cu" "F.Mask" "F.Paste")
			(net "SGPIO_DEBUG_PLD_DIN")
		)
	)
)
